# T6G (Grand Teton) — schematic netlist excerpt (pin names and nets, part order shuffled) for the footprints in the layout excerpt that follows; sources: Cadence DE-HDL packaged netlist, KiCad conversion of 04192023_DAF0TMB3IC0_F0TG_MB_C_brd_V02_OCP.brd

R2820  Q_RES  4.7K 5% EMPTY  pkg 0402LF  page 130 : A = P3V3_AUX ; B = BMC_MONITER_BUF_R

X9011  TP_TDR_4P_FTS  TP_TDR_4P_DIP EMPTY  pkg TH  page 261
  S1  = TDR_DIFF_85_NECK_IN4_DN
  P1  = T1_GND
  P2  = T1_GND
  S2  = TDR_DIFF_85_NECK_IN4_DP

(kicad_pcb
	(version 20260206)
	(generator "pcbnew")
	(generator_version "10.0")
	(general
		(thickness 1.6)
		(legacy_teardrops no)
	)
	(paper "A4")
	(title_block
		(title "04192023_DAF0TMB3IC0_F0TG_MB_C_brd_V02_OCP.brd")
		(comment 1 "Grand Teton / footprints 6991-6992 of 8354")
	)
	(layers
		(0 "F.Cu" signal "TOP")
		(4 "In1.Cu" signal "GND")
		(6 "In2.Cu" signal "IN1")
		(8 "In3.Cu" signal "GND1")
		(10 "In4.Cu" signal "IN2")
		(12 "In5.Cu" signal "GND2")
		(14 "In6.Cu" signal "IN3")
		(16 "In7.Cu" signal "GND3")
		(18 "In8.Cu" signal "VCC")
		(20 "In9.Cu" signal "VCC1")
		(22 "In10.Cu" signal "GND4")
		(24 "In11.Cu" signal "IN4")
		(26 "In12.Cu" signal "GND5")
		(28 "In13.Cu" signal "IN5")
		(30 "In14.Cu" signal "GND6")
		(32 "In15.Cu" signal "IN6")
		(34 "In16.Cu" signal "GND7")
		(2 "B.Cu" signal "BOTTOM")
		(9 "F.Adhes" user "F.Adhesive")
		(11 "B.Adhes" user "B.Adhesive")
		(13 "F.Paste" user "Package Geometry/Pastemask Top")
		(15 "B.Paste" user "Package Geometry/Pastemask Bottom")
		(5 "F.SilkS" user "Ref Des/Silkscreen Top")
		(7 "B.SilkS" user "Ref Des/Silkscreen Bottom")
		(1 "F.Mask" user "Board Geometry/Soldermask Top")
		(3 "B.Mask" user "Board Geometry/Soldermask Bottom")
		(17 "Dwgs.User" user "User.Drawings")
		(19 "Cmts.User" user "User.Comments")
		(21 "Eco1.User" user "User.Eco1")
		(23 "Eco2.User" user "User.Eco2")
		(25 "Edge.Cuts" user "Board Geometry/Outline")
		(27 "Margin" user)
		(31 "F.CrtYd" user "Package Geometry/Place Bound Top")
		(29 "B.CrtYd" user "Package Geometry/Place Bound Bottom")
		(35 "F.Fab" user "Ref Des/Assembly Top")
		(33 "B.Fab" user "Ref Des/Assembly Bottom")
	)
	(footprint ""
		(layer "B.Cu")
		(at 181.182518 -412.949644 90)
		(property "Reference" "R2820"
			(at 0 0 90)
			(layer "B.SilkS")
			(hide yes)
			(effects
				(font
					(size 1.27 1.27)
				)
				(justify mirror)
			)
		)
		(property "Value" ""
			(at 0 0 90)
			(layer "B.Fab")
			(effects
				(font
					(size 1.27 1.27)
				)
				(justify mirror)
			)
		)
		(duplicate_pad_numbers_are_jumpers no)
		(fp_line
			(start 0.7874 -0.4064)
			(end -0.7874 -0.4064)
			(stroke
				(width 0.1524)
				(type default)
			)
			(layer "B.SilkS")
		)
		(fp_line
			(start -0.7874 -0.4064)
			(end -0.7874 0.4064)
			(stroke
				(width 0.1524)
				(type default)
			)
			(layer "B.SilkS")
		)
		(fp_line
			(start 0.7874 0.4064)
			(end 0.7874 -0.4064)
			(stroke
				(width 0.1524)
				(type default)
			)
			(layer "B.SilkS")
		)
		(fp_line
			(start -0.7874 0.4064)
			(end 0.7874 0.4064)
			(stroke
				(width 0.1524)
				(type default)
			)
			(layer "B.SilkS")
		)
		(fp_line
			(start 0.67945 -0.305054)
			(end 0.12065 -0.305054)
			(stroke
				(width 0.1)
				(type default)
			)
			(layer "B.Fab")
		)
		(fp_line
			(start 0.12065 -0.305054)
			(end 0.12065 -0.2794)
			(stroke
				(width 0.1)
				(type default)
			)
			(layer "B.Fab")
		)
		(fp_line
			(start -0.12065 -0.3048)
			(end -0.67945 -0.3048)
			(stroke
				(width 0.1)
				(type default)
			)
			(layer "B.Fab")
		)
		(fp_line
			(start -0.67945 -0.3048)
			(end -0.67945 0.3048)
			(stroke
				(width 0.1)
				(type default)
			)
			(layer "B.Fab")
		)
		(fp_line
			(start 0.12065 -0.2794)
			(end -0.12065 -0.2794)
			(stroke
				(width 0.1)
				(type default)
			)
			(layer "B.Fab")
		)
		(fp_line
			(start -0.12065 -0.2794)
			(end -0.12065 -0.3048)
			(stroke
				(width 0.1)
				(type default)
			)
			(layer "B.Fab")
		)
		(fp_line
			(start 0.12065 0.2794)
			(end 0.12065 0.3048)
			(stroke
				(width 0.1)
				(type default)
			)
			(layer "B.Fab")
		)
		(fp_line
			(start -0.120396 0.2794)
			(end 0.12065 0.2794)
			(stroke
				(width 0.1)
				(type default)
			)
			(layer "B.Fab")
		)
		(fp_line
			(start 0.67945 0.3048)
			(end 0.67945 -0.305054)
			(stroke
				(width 0.1)
				(type default)
			)
			(layer "B.Fab")
		)
		(fp_line
			(start 0.12065 0.3048)
			(end 0.67945 0.3048)
			(stroke
				(width 0.1)
				(type default)
			)
			(layer "B.Fab")
		)
		(fp_line
			(start -0.120396 0.3048)
			(end -0.120396 0.2794)
			(stroke
				(width 0.1)
				(type default)
			)
			(layer "B.Fab")
		)
		(fp_line
			(start -0.67945 0.3048)
			(end -0.120396 0.3048)
			(stroke
				(width 0.1)
				(type default)
			)
			(layer "B.Fab")
		)
		(pad "1" smd circle
			(at 0.40005 0 270)
			(size 0 0)
			(layers "B.Cu" "B.Mask" "B.Paste")
			(net "P3V3_AUX")
		)
		(pad "2" smd circle
			(at -0.40005 0 270)
			(size 0 0)
			(layers "B.Cu" "B.Mask" "B.Paste")
			(net "BMC_MONITER_BUF_R")
		)
	)
	(footprint ""
		(layer "B.Cu")
		(at 511.511042 -457.330048 -90)
		(property "Reference" "X9011"
			(at 4.7244 -1.61163 270)
			(unlocked yes)
			(layer "B.SilkS")
			(effects
				(font
					(size 0.7874 0.5842)
					(thickness 0.1524)
				)
				(justify left mirror)
			)
		)
		(property "Value" ""
			(at 0 0 90)
			(layer "B.Fab")
			(effects
				(font
					(size 1.27 1.27)
				)
				(justify mirror)
			)
		)
		(property "User Part Number" "N_A"
			(at -1.30175 1.27 180)
			(unlocked yes)
			(layer "Cmts.User")
			(hide yes)
			(effects
				(font
					(size 0.635 0.4064)
					(thickness 0.1524)
				)
				(justify mirror)
			)
		)
		(property "Device Type" "TP_TDR_4P_FTS_TH-TP_TDR_4P_DIP,EMPTY,TP15"
			(at -1.30175 1.27 180)
			(unlocked yes)
			(layer "B.Fab")
			(hide yes)
			(effects
				(font
					(size 0.635 0.4064)
					(thickness 0.1524)
				)
				(justify mirror)
			)
		)
		(duplicate_pad_numbers_are_jumpers no)
		(fp_line
			(start -2.54 3.81)
			(end -2.54 3.6703)
			(stroke
				(width 0.1524)
				(type default)
			)
			(layer "B.SilkS")
		)
		(fp_line
			(start 0 3.81)
			(end -2.54 3.81)
			(stroke
				(width 0.1524)
				(type default)
			)
			(layer "B.SilkS")
		)
		(fp_line
			(start 0 3.175)
			(end 0 3.81)
			(stroke
				(width 0.1524)
				(type default)
			)
			(layer "B.SilkS")
		)
		(fp_line
			(start -2.54 1.4097)
			(end -2.54 1.1303)
			(stroke
				(width 0.1524)
				(type default)
			)
			(layer "B.SilkS")
		)
		(fp_line
			(start 0 0.635)
			(end 0 1.905)
			(stroke
				(width 0.1524)
				(type default)
			)
			(layer "B.SilkS")
		)
		(fp_line
			(start -2.54 -1.1303)
			(end -2.54 -1.27)
			(stroke
				(width 0.1524)
				(type default)
			)
			(layer "B.SilkS")
		)
		(fp_line
			(start -2.54 -1.27)
			(end 0 -1.27)
			(stroke
				(width 0.1524)
				(type default)
			)
			(layer "B.SilkS")
		)
		(fp_line
			(start 0 -1.27)
			(end 0 -0.635)
			(stroke
				(width 0.1524)
				(type default)
			)
			(layer "B.SilkS")
		)
		(fp_poly
			(pts
				(xy 0.761746 0) (xy 2.285746 -0.762) (xy 2.285746 0.762)
			)
			(stroke
				(width 0)
				(type default)
			)
			(fill yes)
			(layer "B.SilkS")
		)
		(fp_line
			(start -2.54 3.81)
			(end -2.54 -1.27)
			(stroke
				(width 0.1)
				(type default)
			)
			(layer "B.Fab")
		)
		(fp_line
			(start 0 3.81)
			(end -2.54 3.81)
			(stroke
				(width 0.1)
				(type default)
			)
			(layer "B.Fab")
		)
		(fp_line
			(start -2.54 -1.27)
			(end 0 -1.27)
			(stroke
				(width 0.1)
				(type default)
			)
			(layer "B.Fab")
		)
		(fp_line
			(start 0 -1.27)
			(end 0 3.81)
			(stroke
				(width 0.1)
				(type default)
			)
			(layer "B.Fab")
		)
		(fp_poly
			(pts
				(xy 0.761746 0) (xy 2.285746 -0.762) (xy 2.285746 0.762)
			)
			(stroke
				(width 0)
				(type default)
			)
			(fill yes)
			(layer "B.Fab")
		)
		(pad "1" thru_hole circle
			(at 0 0 90)
			(size 1.0033 1.0033)
			(drill 0.249936)
			(layers "*.Cu" "*.Mask")
			(remove_unused_layers no)
			(net "TDR_DIFF_85_NECK_IN4_DN")
			(clearance 0.10795)
			(padstack
				(mode front_inner_back)
				(layer "Inner"
					(shape circle)
					(size 0.8001 0.8001)
					(clearance 0.1524)
				)
				(layer "B.Cu"
					(shape circle)
					(size 1.0033 1.0033)
					(thermal_gap 0.10795)
					(clearance 0.10795)
				)
			)
		)
		(pad "2" thru_hole circle
			(at -2.54 0 90)
			(size 1.9939 1.9939)
			(drill 0.249936)
			(layers "*.Cu" "*.Mask")
			(remove_unused_layers no)
			(net "T1_GND")
			(clearance 0.10795)
			(padstack
				(mode front_inner_back)
				(layer "Inner"
					(shape circle)
					(size 0.8001 0.8001)
					(clearance 0.1524)
				)
				(layer "B.Cu"
					(shape circle)
					(size 1.9939 1.9939)
					(thermal_gap 0.10795)
					(clearance 0.10795)
				)
			)
		)
		(pad "3" thru_hole circle
			(at -2.54 2.54 90)
			(size 1.9939 1.9939)
			(drill 0.249936)
			(layers "*.Cu" "*.Mask")
			(remove_unused_layers no)
			(net "T1_GND")
			(clearance 0.10795)
			(padstack
				(mode front_inner_back)
				(layer "Inner"
					(shape circle)
					(size 0.8001 0.8001)
					(clearance 0.1524)
				)
				(layer "B.Cu"
					(shape circle)
					(size 1.9939 1.9939)
					(thermal_gap 0.10795)
					(clearance 0.10795)
				)
			)
		)
		(pad "4" thru_hole circle
			(at 0 2.54 90)
			(size 1.0033 1.0033)
			(drill 0.249936)
			(layers "*.Cu" "*.Mask")
			(remove_unused_layers no)
			(net "TDR_DIFF_85_NECK_IN4_DP")
			(clearance 0.10795)
			(padstack
				(mode front_inner_back)
				(layer "Inner"
					(shape circle)
					(size 0.8001 0.8001)
					(clearance 0.1524)
				)
				(layer "B.Cu"
					(shape circle)
					(size 1.0033 1.0033)
					(thermal_gap 0.10795)
					(clearance 0.10795)
				)
			)
		)
	)
)
